# S9S_MB_2U (Grand Teton) — schematic netlist excerpt (pin names and nets, part order shuffled) for the footprints in the layout excerpt that follows; sources: Cadence DE-HDL packaged netlist, KiCad conversion of 03242023_DA0F0TMBIJ0_F0T_Motherboard_J_brd_V01_OCP.brd

R2  Q_RES  100 1% CHIP  pkg 0402LF  page 13 : A = H_CPU_PREQ_QS_GTL_N ; B = H_CPU0_PREQ_QS_GTL_R_N
R3344  Q_RES  1 1% CHIP  pkg 0603LF  page 217 : A = P3V3_AUX ; B = P3V3_AUX_FPGA_VCCIO3
C77  Q_CAP  10UF 16V 10% X6S  pkg C0805  page 112 : A = P12V_S3_AUX_CPU1_NVDIMM ; B = GND

(kicad_pcb
	(version 20260206)
	(generator "pcbnew")
	(generator_version "10.0")
	(general
		(thickness 1.6)
		(legacy_teardrops no)
	)
	(paper "A4")
	(title_block
		(title "03242023_DA0F0TMBIJ0_F0T_Motherboard_J_brd_V01_OCP.brd")
		(comment 1 "Grand Teton / footprints 5342-5344 of 6105")
	)
	(layers
		(0 "F.Cu" signal "TOP")
		(4 "In1.Cu" signal "GND")
		(6 "In2.Cu" signal "IN1")
		(8 "In3.Cu" signal "GND1")
		(10 "In4.Cu" signal "IN2")
		(12 "In5.Cu" signal "GND2")
		(14 "In6.Cu" signal "IN3")
		(16 "In7.Cu" signal "GND3")
		(18 "In8.Cu" signal "VCC")
		(20 "In9.Cu" signal "VCC1")
		(22 "In10.Cu" signal "GND4")
		(24 "In11.Cu" signal "IN4")
		(26 "In12.Cu" signal "GND5")
		(28 "In13.Cu" signal "IN5")
		(30 "In14.Cu" signal "GND6")
		(32 "In15.Cu" signal "IN6")
		(34 "In16.Cu" signal "GND7")
		(2 "B.Cu" signal "BOTTOM")
		(9 "F.Adhes" user "F.Adhesive")
		(11 "B.Adhes" user "B.Adhesive")
		(13 "F.Paste" user "Package Geometry/Pastemask Top")
		(15 "B.Paste" user "Package Geometry/Pastemask Bottom")
		(5 "F.SilkS" user "Ref Des/Silkscreen Top")
		(7 "B.SilkS" user "Ref Des/Silkscreen Bottom")
		(1 "F.Mask" user "Board Geometry/Soldermask Top")
		(3 "B.Mask" user "Board Geometry/Soldermask Bottom")
		(17 "Dwgs.User" user "User.Drawings")
		(19 "Cmts.User" user "User.Comments")
		(21 "Eco1.User" user "User.Eco1")
		(23 "Eco2.User" user "User.Eco2")
		(25 "Edge.Cuts" user "Board Geometry/Outline")
		(27 "Margin" user)
		(31 "F.CrtYd" user "Package Geometry/Place Bound Top")
		(29 "B.CrtYd" user "Package Geometry/Place Bound Bottom")
		(35 "F.Fab" user "Ref Des/Assembly Top")
		(33 "B.Fab" user "Ref Des/Assembly Bottom")
	)
	(footprint ""
		(layer "B.Cu")
		(at 182.68188 -101.564948 180)
		(property "Reference" "R3344"
			(at 0 0 0)
			(layer "B.SilkS")
			(hide yes)
			(effects
				(font
					(size 1.27 1.27)
				)
				(justify mirror)
			)
		)
		(property "Value" ""
			(at 0 0 0)
			(layer "B.Fab")
			(effects
				(font
					(size 1.27 1.27)
				)
				(justify mirror)
			)
		)
		(duplicate_pad_numbers_are_jumpers no)
		(fp_line
			(start 1.2954 0.5842)
			(end 1.2954 -0.5842)
			(stroke
				(width 0.1524)
				(type default)
			)
			(layer "B.SilkS")
		)
		(fp_line
			(start 1.2954 -0.5842)
			(end -1.2954 -0.5842)
			(stroke
				(width 0.1524)
				(type default)
			)
			(layer "B.SilkS")
		)
		(fp_line
			(start -1.2954 0.5842)
			(end 1.2954 0.5842)
			(stroke
				(width 0.1524)
				(type default)
			)
			(layer "B.SilkS")
		)
		(fp_line
			(start -1.2954 -0.5842)
			(end -1.2954 0.5842)
			(stroke
				(width 0.1524)
				(type default)
			)
			(layer "B.SilkS")
		)
		(fp_line
			(start 1.1938 0.4064)
			(end 1.1938 -0.406654)
			(stroke
				(width 0.1)
				(type default)
			)
			(layer "B.Fab")
		)
		(fp_line
			(start 1.1938 -0.406654)
			(end 0.8636 -0.406654)
			(stroke
				(width 0.1)
				(type default)
			)
			(layer "B.Fab")
		)
		(fp_line
			(start 0.8636 0.4572)
			(end 0.8636 0.4318)
			(stroke
				(width 0.1)
				(type default)
			)
			(layer "B.Fab")
		)
		(fp_line
			(start 0.8636 0.4318)
			(end 0.8636 0.4064)
			(stroke
				(width 0.1)
				(type default)
			)
			(layer "B.Fab")
		)
		(fp_line
			(start 0.8636 0.4064)
			(end 1.1938 0.4064)
			(stroke
				(width 0.1)
				(type default)
			)
			(layer "B.Fab")
		)
		(fp_line
			(start 0.8636 -0.406654)
			(end 0.8636 -0.4572)
			(stroke
				(width 0.1)
				(type default)
			)
			(layer "B.Fab")
		)
		(fp_line
			(start 0.8636 -0.4572)
			(end -0.8636 -0.4572)
			(stroke
				(width 0.1)
				(type default)
			)
			(layer "B.Fab")
		)
		(fp_line
			(start -0.8636 0.4572)
			(end 0.8636 0.4572)
			(stroke
				(width 0.1)
				(type default)
			)
			(layer "B.Fab")
		)
		(fp_line
			(start -0.8636 0.4064)
			(end -0.8636 0.4572)
			(stroke
				(width 0.1)
				(type default)
			)
			(layer "B.Fab")
		)
		(fp_line
			(start -0.8636 -0.406654)
			(end -1.1938 -0.406654)
			(stroke
				(width 0.1)
				(type default)
			)
			(layer "B.Fab")
		)
		(fp_line
			(start -0.8636 -0.4572)
			(end -0.8636 -0.406654)
			(stroke
				(width 0.1)
				(type default)
			)
			(layer "B.Fab")
		)
		(fp_line
			(start -1.1938 0.4064)
			(end -0.8636 0.4064)
			(stroke
				(width 0.1)
				(type default)
			)
			(layer "B.Fab")
		)
		(fp_line
			(start -1.1938 -0.406654)
			(end -1.1938 0.4064)
			(stroke
				(width 0.1)
				(type default)
			)
			(layer "B.Fab")
		)
		(pad "1" smd rect
			(at 0.7366 0 90)
			(size 0.7112 0.8128)
			(layers "B.Cu" "B.Mask" "B.Paste")
			(net "P3V3_AUX")
		)
		(pad "2" smd rect
			(at -0.7366 0 90)
			(size 0.7112 0.8128)
			(layers "B.Cu" "B.Mask" "B.Paste")
			(net "P3V3_AUX_FPGA_VCCIO3")
		)
	)
	(footprint ""
		(layer "B.Cu")
		(at 213.422484 -321.554856 -90)
		(property "Reference" "C77"
			(at 0 0 90)
			(layer "B.SilkS")
			(hide yes)
			(effects
				(font
					(size 1.27 1.27)
				)
				(justify mirror)
			)
		)
		(property "Value" ""
			(at 0 0 90)
			(layer "B.Fab")
			(effects
				(font
					(size 1.27 1.27)
				)
				(justify mirror)
			)
		)
		(duplicate_pad_numbers_are_jumpers no)
		(fp_line
			(start -1.524 0.762)
			(end 1.524 0.762)
			(stroke
				(width 0.1524)
				(type default)
			)
			(layer "B.SilkS")
		)
		(fp_line
			(start 1.524 0.762)
			(end 1.524 -0.762)
			(stroke
				(width 0.1524)
				(type default)
			)
			(layer "B.SilkS")
		)
		(fp_line
			(start -1.524 -0.762)
			(end -1.524 0.762)
			(stroke
				(width 0.1524)
				(type default)
			)
			(layer "B.SilkS")
		)
		(fp_line
			(start 1.524 -0.762)
			(end -1.524 -0.762)
			(stroke
				(width 0.1524)
				(type default)
			)
			(layer "B.SilkS")
		)
		(fp_line
			(start -1.1049 0.724916)
			(end -1.1049 -0.724916)
			(stroke
				(width 0.1)
				(type default)
			)
			(layer "B.Fab")
		)
		(fp_line
			(start 1.1049 0.724916)
			(end -1.1049 0.724916)
			(stroke
				(width 0.1)
				(type default)
			)
			(layer "B.Fab")
		)
		(fp_line
			(start -1.1049 -0.724916)
			(end 1.1049 -0.724916)
			(stroke
				(width 0.1)
				(type default)
			)
			(layer "B.Fab")
		)
		(fp_line
			(start 1.1049 -0.724916)
			(end 1.1049 0.724916)
			(stroke
				(width 0.1)
				(type default)
			)
			(layer "B.Fab")
		)
		(pad "1" smd rect
			(at 0.889 0 270)
			(size 1.016 1.27)
			(layers "B.Cu" "B.Mask" "B.Paste")
			(net "P12V_S3_AUX_CPU1_NVDIMM")
		)
		(pad "2" smd rect
			(at -0.889 0 270)
			(size 1.016 1.27)
			(layers "B.Cu" "B.Mask" "B.Paste")
			(net "GND")
		)
	)
	(footprint ""
		(layer "B.Cu")
		(at 313.78144 -193.53911 -90)
		(property "Reference" "R2"
			(at 0 0 90)
			(layer "B.SilkS")
			(hide yes)
			(effects
				(font
					(size 1.27 1.27)
				)
				(justify mirror)
			)
		)
		(property "Value" ""
			(at 0 0 90)
			(layer "B.Fab")
			(effects
				(font
					(size 1.27 1.27)
				)
				(justify mirror)
			)
		)
		(duplicate_pad_numbers_are_jumpers no)
		(fp_line
			(start -0.7874 0.4064)
			(end 0.7874 0.4064)
			(stroke
				(width 0.1524)
				(type default)
			)
			(layer "B.SilkS")
		)
		(fp_line
			(start 0.7874 0.4064)
			(end 0.7874 -0.4064)
			(stroke
				(width 0.1524)
				(type default)
			)
			(layer "B.SilkS")
		)
		(fp_line
			(start -0.7874 -0.4064)
			(end -0.7874 0.4064)
			(stroke
				(width 0.1524)
				(type default)
			)
			(layer "B.SilkS")
		)
		(fp_line
			(start 0.7874 -0.4064)
			(end -0.7874 -0.4064)
			(stroke
				(width 0.1524)
				(type default)
			)
			(layer "B.SilkS")
		)
		(fp_line
			(start -0.67945 0.3048)
			(end -0.120396 0.3048)
			(stroke
				(width 0.1)
				(type default)
			)
			(layer "B.Fab")
		)
		(fp_line
			(start -0.120396 0.3048)
			(end -0.120396 0.2794)
			(stroke
				(width 0.1)
				(type default)
			)
			(layer "B.Fab")
		)
		(fp_line
			(start 0.12065 0.3048)
			(end 0.67945 0.3048)
			(stroke
				(width 0.1)
				(type default)
			)
			(layer "B.Fab")
		)
		(fp_line
			(start 0.67945 0.3048)
			(end 0.67945 -0.305054)
			(stroke
				(width 0.1)
				(type default)
			)
			(layer "B.Fab")
		)
		(fp_line
			(start -0.120396 0.2794)
			(end 0.12065 0.2794)
			(stroke
				(width 0.1)
				(type default)
			)
			(layer "B.Fab")
		)
		(fp_line
			(start 0.12065 0.2794)
			(end 0.12065 0.3048)
			(stroke
				(width 0.1)
				(type default)
			)
			(layer "B.Fab")
		)
		(fp_line
			(start -0.12065 -0.2794)
			(end -0.12065 -0.3048)
			(stroke
				(width 0.1)
				(type default)
			)
			(layer "B.Fab")
		)
		(fp_line
			(start 0.12065 -0.2794)
			(end -0.12065 -0.2794)
			(stroke
				(width 0.1)
				(type default)
			)
			(layer "B.Fab")
		)
		(fp_line
			(start -0.67945 -0.3048)
			(end -0.67945 0.3048)
			(stroke
				(width 0.1)
				(type default)
			)
			(layer "B.Fab")
		)
		(fp_line
			(start -0.12065 -0.3048)
			(end -0.67945 -0.3048)
			(stroke
				(width 0.1)
				(type default)
			)
			(layer "B.Fab")
		)
		(fp_line
			(start 0.12065 -0.305054)
			(end 0.12065 -0.2794)
			(stroke
				(width 0.1)
				(type default)
			)
			(layer "B.Fab")
		)
		(fp_line
			(start 0.67945 -0.305054)
			(end 0.12065 -0.305054)
			(stroke
				(width 0.1)
				(type default)
			)
			(layer "B.Fab")
		)
		(pad "1" smd circle
			(at 0.40005 0 90)
			(size 0 0)
			(layers "B.Cu" "B.Mask" "B.Paste")
			(net "H_CPU_PREQ_QS_GTL_N")
		)
		(pad "2" smd circle
			(at -0.40005 0 90)
			(size 0 0)
			(layers "B.Cu" "B.Mask" "B.Paste")
			(net "H_CPU0_PREQ_QS_GTL_R_N")
		)
	)
)
